# T6G (Grand Teton) — schematic netlist excerpt (pin names and nets, part order shuffled) for the footprints in the layout excerpt that follows; sources: Cadence DE-HDL packaged netlist, KiCad conversion of 04192023_DAF0TMB3IC0_F0TG_MB_C_brd_V02_OCP.brd

PC124_6  Q_CAP  0.1UF 25V 10% X7R  pkg 0402  page 213 : A = PVDDCR_CPU0_P1_VCCS ; B = GND
PR4004  Q_RES  17.8K 1% CHIP  pkg 0402LF  page 152 : A = P12V_SCM_CB ; B = GND

(kicad_pcb
	(version 20260206)
	(generator "pcbnew")
	(generator_version "10.0")
	(general
		(thickness 1.6)
		(legacy_teardrops no)
	)
	(paper "A4")
	(title_block
		(title "04192023_DAF0TMB3IC0_F0TG_MB_C_brd_V02_OCP.brd")
		(comment 1 "Grand Teton / footprints 3340-3341 of 8354")
	)
	(layers
		(0 "F.Cu" signal "TOP")
		(4 "In1.Cu" signal "GND")
		(6 "In2.Cu" signal "IN1")
		(8 "In3.Cu" signal "GND1")
		(10 "In4.Cu" signal "IN2")
		(12 "In5.Cu" signal "GND2")
		(14 "In6.Cu" signal "IN3")
		(16 "In7.Cu" signal "GND3")
		(18 "In8.Cu" signal "VCC")
		(20 "In9.Cu" signal "VCC1")
		(22 "In10.Cu" signal "GND4")
		(24 "In11.Cu" signal "IN4")
		(26 "In12.Cu" signal "GND5")
		(28 "In13.Cu" signal "IN5")
		(30 "In14.Cu" signal "GND6")
		(32 "In15.Cu" signal "IN6")
		(34 "In16.Cu" signal "GND7")
		(2 "B.Cu" signal "BOTTOM")
		(9 "F.Adhes" user "F.Adhesive")
		(11 "B.Adhes" user "B.Adhesive")
		(13 "F.Paste" user "Package Geometry/Pastemask Top")
		(15 "B.Paste" user "Package Geometry/Pastemask Bottom")
		(5 "F.SilkS" user "Ref Des/Silkscreen Top")
		(7 "B.SilkS" user "Ref Des/Silkscreen Bottom")
		(1 "F.Mask" user "Board Geometry/Soldermask Top")
		(3 "B.Mask" user "Board Geometry/Soldermask Bottom")
		(17 "Dwgs.User" user "User.Drawings")
		(19 "Cmts.User" user "User.Comments")
		(21 "Eco1.User" user "User.Eco1")
		(23 "Eco2.User" user "User.Eco2")
		(25 "Edge.Cuts" user "Board Geometry/Outline")
		(27 "Margin" user)
		(31 "F.CrtYd" user "Package Geometry/Place Bound Top")
		(29 "B.CrtYd" user "Package Geometry/Place Bound Bottom")
		(35 "F.Fab" user "Ref Des/Assembly Top")
		(33 "B.Fab" user "Ref Des/Assembly Bottom")
	)
	(footprint ""
		(layer "F.Cu")
		(at 68.341494 -164.071046 -90)
		(property "Reference" "PC124_6"
			(at 0 0 270)
			(layer "F.SilkS")
			(hide yes)
			(effects
				(font
					(size 1.27 1.27)
				)
			)
		)
		(property "Value" ""
			(at 0 0 270)
			(layer "F.Fab")
			(effects
				(font
					(size 1.27 1.27)
				)
			)
		)
		(duplicate_pad_numbers_are_jumpers no)
		(fp_line
			(start -0.7874 0.4064)
			(end -0.7874 -0.4064)
			(stroke
				(width 0.1524)
				(type default)
			)
			(layer "F.SilkS")
		)
		(fp_line
			(start 0.7874 0.4064)
			(end -0.7874 0.4064)
			(stroke
				(width 0.1524)
				(type default)
			)
			(layer "F.SilkS")
		)
		(fp_line
			(start -0.7874 -0.4064)
			(end 0.7874 -0.4064)
			(stroke
				(width 0.1524)
				(type default)
			)
			(layer "F.SilkS")
		)
		(fp_line
			(start 0.7874 -0.4064)
			(end 0.7874 0.4064)
			(stroke
				(width 0.1524)
				(type default)
			)
			(layer "F.SilkS")
		)
		(fp_line
			(start -0.67945 0.3048)
			(end -0.67945 -0.305054)
			(stroke
				(width 0.1)
				(type default)
			)
			(layer "F.Fab")
		)
		(fp_line
			(start -0.12065 0.3048)
			(end -0.67945 0.3048)
			(stroke
				(width 0.1)
				(type default)
			)
			(layer "F.Fab")
		)
		(fp_line
			(start 0.120396 0.3048)
			(end 0.120396 0.2794)
			(stroke
				(width 0.1)
				(type default)
			)
			(layer "F.Fab")
		)
		(fp_line
			(start 0.67945 0.3048)
			(end 0.120396 0.3048)
			(stroke
				(width 0.1)
				(type default)
			)
			(layer "F.Fab")
		)
		(fp_line
			(start -0.12065 0.2794)
			(end -0.12065 0.3048)
			(stroke
				(width 0.1)
				(type default)
			)
			(layer "F.Fab")
		)
		(fp_line
			(start 0.120396 0.2794)
			(end -0.12065 0.2794)
			(stroke
				(width 0.1)
				(type default)
			)
			(layer "F.Fab")
		)
		(fp_line
			(start -0.12065 -0.2794)
			(end 0.12065 -0.2794)
			(stroke
				(width 0.1)
				(type default)
			)
			(layer "F.Fab")
		)
		(fp_line
			(start 0.12065 -0.2794)
			(end 0.12065 -0.3048)
			(stroke
				(width 0.1)
				(type default)
			)
			(layer "F.Fab")
		)
		(fp_line
			(start 0.12065 -0.3048)
			(end 0.67945 -0.3048)
			(stroke
				(width 0.1)
				(type default)
			)
			(layer "F.Fab")
		)
		(fp_line
			(start 0.67945 -0.3048)
			(end 0.67945 0.3048)
			(stroke
				(width 0.1)
				(type default)
			)
			(layer "F.Fab")
		)
		(fp_line
			(start -0.67945 -0.305054)
			(end -0.12065 -0.305054)
			(stroke
				(width 0.1)
				(type default)
			)
			(layer "F.Fab")
		)
		(fp_line
			(start -0.12065 -0.305054)
			(end -0.12065 -0.2794)
			(stroke
				(width 0.1)
				(type default)
			)
			(layer "F.Fab")
		)
		(pad "1" smd circle
			(at -0.40005 0 270)
			(size 0 0)
			(layers "F.Cu" "F.Mask" "F.Paste")
			(net "PVDDCR_CPU0_P1_VCCS")
		)
		(pad "2" smd circle
			(at 0.40005 0 270)
			(size 0 0)
			(layers "F.Cu" "F.Mask" "F.Paste")
			(net "GND")
		)
	)
	(footprint ""
		(layer "F.Cu")
		(at 185.928762 -25.899872 180)
		(property "Reference" "PR4004"
			(at 0 0 180)
			(layer "F.SilkS")
			(hide yes)
			(effects
				(font
					(size 1.27 1.27)
				)
			)
		)
		(property "Value" ""
			(at 0 0 180)
			(layer "F.Fab")
			(effects
				(font
					(size 1.27 1.27)
				)
			)
		)
		(duplicate_pad_numbers_are_jumpers no)
		(fp_line
			(start 0.7874 0.4064)
			(end -0.7874 0.4064)
			(stroke
				(width 0.1524)
				(type default)
			)
			(layer "F.SilkS")
		)
		(fp_line
			(start 0.7874 -0.4064)
			(end 0.7874 0.4064)
			(stroke
				(width 0.1524)
				(type default)
			)
			(layer "F.SilkS")
		)
		(fp_line
			(start -0.7874 0.4064)
			(end -0.7874 -0.4064)
			(stroke
				(width 0.1524)
				(type default)
			)
			(layer "F.SilkS")
		)
		(fp_line
			(start -0.7874 -0.4064)
			(end 0.7874 -0.4064)
			(stroke
				(width 0.1524)
				(type default)
			)
			(layer "F.SilkS")
		)
		(fp_line
			(start 0.67945 0.3048)
			(end 0.120396 0.3048)
			(stroke
				(width 0.1)
				(type default)
			)
			(layer "F.Fab")
		)
		(fp_line
			(start 0.67945 -0.3048)
			(end 0.67945 0.3048)
			(stroke
				(width 0.1)
				(type default)
			)
			(layer "F.Fab")
		)
		(fp_line
			(start 0.12065 -0.2794)
			(end 0.12065 -0.3048)
			(stroke
				(width 0.1)
				(type default)
			)
			(layer "F.Fab")
		)
		(fp_line
			(start 0.12065 -0.3048)
			(end 0.67945 -0.3048)
			(stroke
				(width 0.1)
				(type default)
			)
			(layer "F.Fab")
		)
		(fp_line
			(start 0.120396 0.3048)
			(end 0.120396 0.2794)
			(stroke
				(width 0.1)
				(type default)
			)
			(layer "F.Fab")
		)
		(fp_line
			(start 0.120396 0.2794)
			(end -0.12065 0.2794)
			(stroke
				(width 0.1)
				(type default)
			)
			(layer "F.Fab")
		)
		(fp_line
			(start -0.12065 0.3048)
			(end -0.67945 0.3048)
			(stroke
				(width 0.1)
				(type default)
			)
			(layer "F.Fab")
		)
		(fp_line
			(start -0.12065 0.2794)
			(end -0.12065 0.3048)
			(stroke
				(width 0.1)
				(type default)
			)
			(layer "F.Fab")
		)
		(fp_line
			(start -0.12065 -0.2794)
			(end 0.12065 -0.2794)
			(stroke
				(width 0.1)
				(type default)
			)
			(layer "F.Fab")
		)
		(fp_line
			(start -0.12065 -0.305054)
			(end -0.12065 -0.2794)
			(stroke
				(width 0.1)
				(type default)
			)
			(layer "F.Fab")
		)
		(fp_line
			(start -0.67945 0.3048)
			(end -0.67945 -0.305054)
			(stroke
				(width 0.1)
				(type default)
			)
			(layer "F.Fab")
		)
		(fp_line
			(start -0.67945 -0.305054)
			(end -0.12065 -0.305054)
			(stroke
				(width 0.1)
				(type default)
			)
			(layer "F.Fab")
		)
		(pad "1" smd circle
			(at -0.40005 0 180)
			(size 0 0)
			(layers "F.Cu" "F.Mask" "F.Paste")
			(net "P12V_SCM_CB")
		)
		(pad "2" smd circle
			(at 0.40005 0 180)
			(size 0 0)
			(layers "F.Cu" "F.Mask" "F.Paste")
			(net "GND")
		)
	)
)
